# BASEBOARD_FAB2 (Tioga Pass) — schematic netlist excerpt (pin names and nets, part order shuffled) for the footprints in the layout excerpt that follows; sources: Cadence DE-HDL packaged netlist, KiCad conversion of Wiwynn_Tioga_Pass_MB.brd

F30W1  POLYSW-1D1A6V-2-GP-U  pkg DISCRET-G7  page 253 : \1\ = P5V_STBY ; \2\ = P5V_STBY_USBC
C844  CAP  0.22UF 16V 10% X7R  pkg 0402  page 244 : A = P3E_CPU0_PE1_PCH_TXN<9> ; B = P3E_CPU0_PE1_PCH_CON_TXN<9>

(kicad_pcb
	(version 20260206)
	(generator "pcbnew")
	(generator_version "10.0")
	(general
		(thickness 1.6)
		(legacy_teardrops no)
	)
	(paper "A4")
	(title_block
		(title "Wiwynn_Tioga_Pass_MB.brd")
		(comment 1 "Tioga Pass / footprints 324-325 of 4770")
	)
	(layers
		(0 "F.Cu" signal "TOP")
		(4 "In1.Cu" signal "L2GND")
		(6 "In2.Cu" signal "L3")
		(8 "In3.Cu" signal "L4GND")
		(10 "In4.Cu" signal "L5")
		(12 "In5.Cu" signal "L6GND")
		(14 "In6.Cu" signal "L7VCC")
		(16 "In7.Cu" signal "L8VCC")
		(18 "In8.Cu" signal "L9GND")
		(20 "In9.Cu" signal "L10")
		(22 "In10.Cu" signal "L11GND")
		(24 "In11.Cu" signal "L12")
		(26 "In12.Cu" signal "L13GND")
		(2 "B.Cu" signal "BOTTOM")
		(9 "F.Adhes" user "F.Adhesive")
		(11 "B.Adhes" user "B.Adhesive")
		(13 "F.Paste" user "Package Geometry/Pastemask Top")
		(15 "B.Paste" user "Package Geometry/Pastemask Bottom")
		(5 "F.SilkS" user "Ref Des/Silkscreen Top")
		(7 "B.SilkS" user "Ref Des/Silkscreen Bottom")
		(1 "F.Mask" user "Board Geometry/Soldermask Top")
		(3 "B.Mask" user "Board Geometry/Soldermask Bottom")
		(17 "Dwgs.User" user "User.Drawings")
		(19 "Cmts.User" user "User.Comments")
		(21 "Eco1.User" user "User.Eco1")
		(23 "Eco2.User" user "User.Eco2")
		(25 "Edge.Cuts" user "Board Geometry/Outline")
		(27 "Margin" user)
		(31 "F.CrtYd" user "Package Geometry/Place Bound Top")
		(29 "B.CrtYd" user "Package Geometry/Place Bound Bottom")
		(35 "F.Fab" user "Ref Des/Assembly Top")
		(33 "B.Fab" user "Ref Des/Assembly Bottom")
	)
	(footprint ""
		(layer "F.Cu")
		(at 487.39679 -58.51144)
		(property "Reference" "F30W1"
			(at 0 0 0)
			(layer "F.SilkS")
			(hide yes)
			(effects
				(font
					(size 1.27 1.27)
				)
			)
		)
		(property "Value" "*"
			(at -2.3241 1.30175 0)
			(unlocked yes)
			(layer "F.Fab")
			(hide yes)
			(effects
				(font
					(size 0.889 0.889)
					(thickness 0.1524)
				)
			)
		)
		(property "Device Type" "POLYSW-1D1A6V-2-GP-U_DISCRET-GA"
			(at -2.3241 -0.22225 0)
			(unlocked yes)
			(layer "F.Fab")
			(hide yes)
			(effects
				(font
					(size 0.889 0.889)
					(thickness 0.1524)
				)
			)
		)
		(duplicate_pad_numbers_are_jumpers no)
		(fp_line
			(start -1.2065 -2.2479)
			(end -1.2065 2.2479)
			(stroke
				(width 0.1524)
				(type default)
			)
			(layer "F.SilkS")
		)
		(fp_line
			(start -1.2065 2.2479)
			(end 1.2065 2.2479)
			(stroke
				(width 0.1524)
				(type default)
			)
			(layer "F.SilkS")
		)
		(fp_line
			(start 1.2065 -2.2479)
			(end -1.2065 -2.2479)
			(stroke
				(width 0.1524)
				(type default)
			)
			(layer "F.SilkS")
		)
		(fp_line
			(start 1.2065 2.2479)
			(end 1.2065 -2.2479)
			(stroke
				(width 0.1524)
				(type default)
			)
			(layer "F.SilkS")
		)
		(fp_rect
			(start -0.8255 1.6002)
			(end 0.8255 -1.6002)
			(stroke
				(width 0)
				(type default)
			)
			(fill no)
			(layer "F.CrtYd")
		)
		(fp_poly
			(pts
				(xy -1.4605 2.3241) (xy -1.4605 -2.3241) (xy 1.4605 -2.3241) (xy 1.4605 1.59512) (xy 0.8255 1.59512)
				(xy 0.8255 -1.6002) (xy -0.8255 -1.6002) (xy -0.8255 1.6002) (xy 1.4605 1.6002) (xy 1.4605 2.3241)
			)
			(stroke
				(width 0)
				(type default)
			)
			(fill no)
			(layer "F.CrtYd")
		)
		(fp_rect
			(start -1.4605 2.3241)
			(end 1.4605 -2.3241)
			(stroke
				(width 0)
				(type default)
			)
			(fill no)
			(layer "F.Fab")
		)
		(pad "1" smd rect
			(at 0 -1.417574)
			(size 1.905 1.143)
			(layers "F.Cu" "F.Mask" "F.Paste")
			(net "P5V_STBY")
		)
		(pad "2" smd rect
			(at 0 1.417574)
			(size 1.905 1.143)
			(layers "F.Cu" "F.Mask" "F.Paste")
			(net "P5V_STBY_USBC")
		)
	)
	(footprint ""
		(layer "F.Cu")
		(at 339.222588 -119.211598 -90)
		(property "Reference" "C844"
			(at -0.8382 -0.67818 270)
			(unlocked yes)
			(layer "F.SilkS")
			(effects
				(font
					(size 0.4064 0.254)
					(thickness 0.1524)
				)
				(justify left)
			)
		)
		(property "Value" ""
			(at 0 0 270)
			(layer "F.Fab")
			(effects
				(font
					(size 1.27 1.27)
				)
			)
		)
		(duplicate_pad_numbers_are_jumpers no)
		(fp_poly
			(pts
				(xy 0.3048 -0.1016) (xy 0.3048 0.9906) (xy -0.3048 0.9906) (xy -0.3048 -0.1016)
			)
			(stroke
				(width 0)
				(type default)
			)
			(fill no)
			(layer "F.CrtYd")
		)
		(fp_line
			(start -0.3048 0.9906)
			(end 0.3048 0.9906)
			(stroke
				(width 0.1)
				(type default)
			)
			(layer "F.Fab")
		)
		(fp_line
			(start 0.3048 0.9906)
			(end 0.3048 -0.1016)
			(stroke
				(width 0.1)
				(type default)
			)
			(layer "F.Fab")
		)
		(fp_line
			(start -0.3048 -0.1016)
			(end -0.3048 0.9906)
			(stroke
				(width 0.1)
				(type default)
			)
			(layer "F.Fab")
		)
		(fp_line
			(start 0.3048 -0.1016)
			(end -0.3048 -0.1016)
			(stroke
				(width 0.1)
				(type default)
			)
			(layer "F.Fab")
		)
		(pad "1" smd rect
			(at 0 0 270)
			(size 0.508 0.508)
			(layers "F.Cu" "F.Mask" "F.Paste")
			(net "P3E_CPU0_PE1_PCH_TXN<9>")
		)
		(pad "2" smd rect
			(at 0 0.889 270)
			(size 0.508 0.508)
			(layers "F.Cu" "F.Mask" "F.Paste")
			(net "P3E_CPU0_PE1_PCH_CON_TXN<9>")
		)
		(zone
			(layer "F.Cu")
			(hatch none 0.5)
			(connect_pads
				(clearance 0)
			)
			(min_thickness 0.25)
			(keepout
				(tracks not_allowed)
				(vias allowed)
				(pads allowed)
				(copperpour not_allowed)
				(footprints allowed)
			)
			(placement
				(enabled no)
				(sheetname "")
			)
			(fill
				(thermal_gap 0.5)
				(thermal_bridge_width 0.5)
				(island_removal_mode 0)
			)
			(polygon
				(pts
					(xy 338.587588 -119.465598) (xy 338.587588 -118.957598) (xy 338.968588 -118.957598) (xy 338.968588 -119.465598)
				)
			)
		)
		(zone
			(layer "F.Cu")
			(hatch none 0.5)
			(connect_pads
				(clearance 0)
			)
			(min_thickness 0.25)
			(keepout
				(tracks allowed)
				(vias not_allowed)
				(pads allowed)
				(copperpour not_allowed)
				(footprints allowed)
			)
			(placement
				(enabled no)
				(sheetname "")
			)
			(fill
				(thermal_gap 0.5)
				(thermal_bridge_width 0.5)
				(island_removal_mode 0)
			)
			(polygon
				(pts
					(xy 338.968588 -119.465598) (xy 338.968588 -118.957598) (xy 338.587588 -118.957598) (xy 338.587588 -119.465598)
				)
			)
		)
	)
)
